FILE_TYPE = CONNECTIVITY;
{Allegro Design Entry HDL 17.2-2016 S081 (4005846) 1/11/2022}
"PAGE_NUMBER" = 253;
0"NC";
1"PVCCIN_CPU0_PVCC\g";
2"P5V\g";
3"P3V3\g";
4"SW_P12V_PVCCIN_CPU0_FLT\g";
5"PVCCIN_CPU0\g";
6"PVCCIN_CPU0\g";
7"SW_P12V_PVCCIN_CPU0_FLT\g";
8"P12V_AUX\g";
9"PVCCIN_CPU0\g";
10"PVCCIN_CPU0\g";
11"SW_P12V_PVCCIN_CPU0_FLT\g";
12"GND\g";
13"GND\g";
14"GND\g";
15"GND\g";
16"GND\g";
17"GND\g";
18"GND\g";
19"GND\g";
20"GND\g";
21"GND\g";
22"GND\g";
23"GND\g";
24"GND\g";
25"GND\g";
26"GND\g";
27"GND\g";
28"GND\g";
29"GND\g";
30"IND_P0_CPL2";
31"IND_P0_CPL3";
32"SW_PVCCIN_CPU0_BOOT1_R";
33"IND_P0_CPL1";
34"SW_PVCCIN_CPU0_BOOTR1";
35"SW_PVCCIN_CPU0_SW1";
36"SW_PVCCIN_CPU0_BOOT1";
37"PVCCIN_CPU0_VOS1";
38"PVCCIN_CPU0_PVCC";
39"PVCCIN_CPU0_VDD1";
40"PVCCIN_CPU0_IMON1";
41"PVCCIN_CPU0_PWM1";
42"PVCCIN_CPU0_ATSEN";
43"PVCCIN_CPU0_VREF"CDS_PHYS_NET_NAME"PVCCIN_CPU0_VREF";
44"PVCCIN_CPU0_LSET1";
45"SW_PVCCIN_CPU0_BOOT2_R";
46"IND_P0_CPL2";
47"SW_PVCCIN_CPU0_SW2";
48"SW_PVCCIN_CPU0_BOOTR2";
49"SW_PVCCIN_CPU0_BOOT2";
50"PVCCIN_CPU0_VOS2";
51"PVCCIN_CPU0_VDD2";
52"PVCCIN_CPU0_IMON2";
53"PVCCIN_CPU0_VREF"CDS_PHYS_NET_NAME"PVCCIN_CPU0_VREF";
54"PVCCIN_CPU0_ATSEN";
55"PVCCIN_CPU0_PWM2";
56"PVCCIN_CPU0_LSET2";
%"UNIVERSAL_GND"
"1","(-4200,-2850)","0","logical_power","I1";
;
HDL_POWER"GND"
CDS_LIB"logical_power";
"A"12;
%"UNIVERSAL_GND"
"1","(-3800,-1875)","0","logical_power","I10";
;
HDL_POWER"GND"
CDS_LIB"logical_power";
"A"14;
%"Q_CAP"
"2","(-3475,-2325)","0","pure_quanta","I11";
;
PART_NUMBER"CH4104K1B00"
PACK_TYPE"0402"
MATERIAL"X7R"
TOLERANCE"10%"
VOLTAGE"25V"
VALUE"0.1UF"
LOCATION"PC1355"
CDS_LIB"pure_quanta"
$SEC"1"
CDS_SEC"1";
"A"
$PN"1"13;
"B"
$PN"2"53;
%"Q_RES"
"2","(-3800,-1125)","0","pure_quanta","I12";
;
PART_NUMBER"CS-2202FB01"
PACK_TYPE"0402LF"
VALUE"2.2"
TOLERANCE"1%"
MATERIAL"CHIP"
WATTAGE"1/16W"
LOCATION"PR152"
CDS_LIB"pure_quanta"
LOCATION"PR152"
$SEC"1"
CDS_SEC"1";
"A"
$PN"1"1;
"B"
$PN"2"51;
%"VCC15"
"1","(-3800,-800)","0","logical_power","I13";
;
HDL_POWER"PVCCIN_CPU0_PVCC"
CDS_LIB"logical_power";
"A"1;
%"UNIVERSAL_GND"
"1","(-3375,-1350)","0","logical_power","I14";
;
HDL_POWER"GND"
CDS_LIB"logical_power";
"A"15;
%"Q_CAP"
"1","(-3375,-1125)","0","pure_quanta","I15";
;
PART_NUMBER"CH5222KEB01"
PACK_TYPE"C0402"
VOLTAGE"10V"
VALUE"2.2UF"
TOLERANCE"10%"
MATERIAL"X6S"
LOCATION"PC294_P0_2"
CDS_LIB"pure_quanta"
LOCATION"PC294_P0_2"
$SEC"1"
CDS_SEC"1";
"B"
$PN"2"15;
"A"
$PN"1"1;
%"UNIVERSAL_GND"
"1","(-1625,-2850)","0","logical_power","I16";
;
HDL_POWER"GND"
CDS_LIB"logical_power";
"A"16;
%"Q_RES"
"1","(-1025,-1675)","0","pure_quanta","I18";
;
PART_NUMBER"CS-3302FB01"
TOLERANCE"1%"
VALUE"3.3"
WATTAGE"1/16W"
MATERIAL"CHIP"
PACK_TYPE"0402LF"
LOCATION"PR1786"
CDS_LIB"pure_quanta"
$SEC"1"
CDS_SEC"1";
"B"
$PN"2"45;
"A"
$PN"1"49;
%"Q_CAP"
"1","(-1475,-1225)","0","pure_quanta","I19";
;
PART_NUMBER"TMP_QCH2336K1B12"
TOLERANCE"10%"
MATERIAL"X7R"
PACK_TYPE"0402"
VALUE"3300PF"
VOLTAGE"50V"
LOCATION"PC296_P0_2"
CDS_LIB"pure_quanta"
LOCATION"PC296_P0_2"
$SEC"1"
CDS_SEC"1";
"B"
$PN"2"22;
"A"
$PN"1"4;
%"Q_RES"
"2","(-4200,-2625)","2","pure_quanta","I2";
;
PART_NUMBER"CS28872FB01"
PACK_TYPE"0402LF"
VALUE"8.87K"
TOLERANCE"1%"
MATERIAL"EMPTY"
WATTAGE"1/16W"
LOCATION"PR150"
CDS_LIB"pure_quanta"
$SEC"1"
CDS_SEC"1";
"A"
$PN"1"56;
"B"
$PN"2"12;
%"Q_CAP"
"1","(-225,-1875)","2","pure_quanta","I20";
;
PART_NUMBER"CH4106K1B01"
VOLTAGE"50V"
VALUE"100NF"
TOLERANCE"10%"
MATERIAL"X7R"
PACK_TYPE"C0402"
LOCATION"PC300"
CDS_LIB"pure_quanta"
$SEC"1"
CDS_SEC"1";
"B"
$PN"2"48;
"A"
$PN"1"45;
%"Q_INDUCTOR4P_14"
"1","(250,-2250)","0","pure_quanta","I21";
;
PART_NUMBER"CV+15^0TZ04"
VALUE"150NH"
MATERIAL"IND"
PART_TYPE"SMLF"
LOCATION"PL13"
SEC_TYPE""
CDS_LIB"pure_quanta"
NEEDS_NO_SIZE"TRUE"
SEC"1";
"1"
$PN"1"47;
"4"
$PN"4"6;
"3"
$PN"3"31;
"2"
$PN"2"46;
%"Q_CAP"
"1","(-1075,-1225)","0","pure_quanta","I22";
;
PART_NUMBER"CH5103KEB01"
PACK_TYPE"C0402"
VOLTAGE"16V"
VALUE"1UF"
TOLERANCE"10%"
MATERIAL"X6S"
LOCATION"PC298_P0_2"
CDS_LIB"pure_quanta"
LOCATION"PC298_P0_2"
$SEC"1"
CDS_SEC"1";
"B"
$PN"2"22;
"A"
$PN"1"4;
%"Q_CAP"
"1","(-675,-1225)","0","pure_quanta","I23";
;
PART_NUMBER"CH6223MEA01"
TOLERANCE"20%"
PACK_TYPE"C0805"
VALUE"22UF"
MATERIAL"X6S"
VOLTAGE"16V"
LOCATION"PC302_P0_2"
CDS_LIB"pure_quanta"
LOCATION"PC302_P0_2"
$SEC"1"
CDS_SEC"1";
"B"
$PN"2"22;
"A"
$PN"1"4;
%"Q_CAP"
"1","(-275,-1225)","0","pure_quanta","I24";
;
PART_NUMBER"CH6223MEA01"
TOLERANCE"20%"
MATERIAL"X6S"
VOLTAGE"16V"
VALUE"22UF"
PACK_TYPE"C0805"
LOCATION"PC304_P0_2"
CDS_LIB"pure_quanta"
LOCATION"PC304_P0_2"
$SEC"1"
CDS_SEC"1";
"B"
$PN"2"22;
"A"
$PN"1"4;
%"UNIVERSAL_GND"
"1","(-4275,400)","0","logical_power","I25";
;
HDL_POWER"GND"
CDS_LIB"logical_power";
"A"17;
%"Q_RES"
"2","(-4325,2375)","0","pure_quanta","I26";
;
PART_NUMBER"CS00002JB13"
PACK_TYPE"0402LF"
VALUE"0"
TOLERANCE"5%"
WATTAGE"1/16W"
MATERIAL"CHIP"
LOCATION"PR402"
CDS_LIB"pure_quanta"
$SEC"1"
CDS_SEC"1";
"A"
$PN"1"2;
"B"
$PN"2"38;
%"VCC15"
"1","(-4325,2600)","0","logical_power","I27";
;
HDL_POWER"P5V"
CDS_LIB"logical_power";
"A"2;
%"UNIVERSAL_GND"
"1","(-4175,-25)","0","logical_power","I28";
;
HDL_POWER"GND"
CDS_LIB"logical_power";
"A"18;
%"Q_RES"
"2","(-4175,200)","2","pure_quanta","I29";
;
PART_NUMBER"CS28872FB01"
PACK_TYPE"0402LF"
VALUE"8.87K"
TOLERANCE"1%"
MATERIAL"EMPTY"
WATTAGE"1/16W"
LOCATION"PR151"
CDS_LIB"pure_quanta"
$SEC"1"
CDS_SEC"1";
"A"
$PN"1"44;
"B"
$PN"2"18;
%"UNIVERSAL_GND"
"1","(-4300,-2400)","0","logical_power","I3";
;
HDL_POWER"GND"
CDS_LIB"logical_power";
"A"13;
%"Q_CAP"
"2","(-3450,500)","0","pure_quanta","I34";
;
PART_NUMBER"CH4104K1B00"
PACK_TYPE"0402"
MATERIAL"X7R"
TOLERANCE"10%"
VOLTAGE"25V"
VALUE"0.1UF"
LOCATION"PC1356"
CDS_LIB"pure_quanta"
$SEC"1"
CDS_SEC"1";
"A"
$PN"1"17;
"B"
$PN"2"43;
%"UNIVERSAL_GND"
"1","(-3775,950)","0","logical_power","I35";
;
HDL_POWER"GND"
CDS_LIB"logical_power";
"A"19;
%"Q_CAP"
"1","(-3775,1200)","0","pure_quanta","I36";
;
PART_NUMBER"CH5222KEB01"
PACK_TYPE"C0402"
VOLTAGE"10V"
VALUE"2.2UF"
TOLERANCE"10%"
MATERIAL"X6S"
LOCATION"PC293"
CDS_LIB"pure_quanta"
LOCATION"PC293"
$SEC"1"
CDS_SEC"1";
"B"
$PN"2"19;
"A"
$PN"1"39;
%"Q_RES"
"2","(-3775,1700)","0","pure_quanta","I37";
;
PART_NUMBER"CS-2202FB01"
VALUE"2.2"
PACK_TYPE"0402LF"
TOLERANCE"1%"
MATERIAL"CHIP"
WATTAGE"1/16W"
LOCATION"PR153"
CDS_LIB"pure_quanta"
LOCATION"PR153"
$SEC"1"
CDS_SEC"1";
"A"
$PN"1"38;
"B"
$PN"2"39;
%"UNIVERSAL_GND"
"1","(-3350,1475)","0","logical_power","I38";
;
HDL_POWER"GND"
CDS_LIB"logical_power";
"A"20;
%"Q_CAP"
"1","(-3350,1700)","0","pure_quanta","I39";
;
PART_NUMBER"CH5222KEB01"
PACK_TYPE"C0402"
VOLTAGE"10V"
VALUE"2.2UF"
TOLERANCE"10%"
MATERIAL"X6S"
LOCATION"PC295_P0_1"
CDS_LIB"pure_quanta"
LOCATION"PC295_P0_1"
$SEC"1"
CDS_SEC"1";
"B"
$PN"2"20;
"A"
$PN"1"38;
%"ISL99390FRZTR5935"
"1","(-2250,700)","0","pure_quanta","I40";
;
PART_NUMBER"AL099390004"
VALUE"ISL99390FRZ-TR5935"
MATERIAL"IC"
PART_TYPE"SMLF"
LOCATION"PU13_P0_1"
NEEDS_NO_SIZE"TRUE"
CDS_LMAN_SYM_OUTLINE"-300,700,250,-650"
CDS_LIB"pure_quanta"
$SEC"1"
CDS_SEC"1";
"PGND2"
$PN"7_9-20_24"21;
"GL2"
$PN"41"0;
"GL1"
$PN"6"0;
"DNC"
$PN"31"0;
"EN"
$PN"35"39;
"PGND3"
$PN"40"21;
"VOS"
$PN"1"37;
"VIN2"
$PN"30"7;
"PGND1"
$PN"5"21;
"SW"
$PN"10_19"35;
"LSET"
$PN"37"44;
"IOUT"
$PN"38"40;
"TOUT_FLT"
$PN"36"42;
"PVCC"
$PN"4"38;
"PHASE"
$PN"32"34;
"VIN1"
$PN"25_29"7;
"BOOT"
$PN"33"36;
"AGND"
$PN"2"21;
"VCC"
$PN"3"39;
"REFIN"
$PN"39"43;
"PWM"
$PN"34"41;
%"VCC15"
"1","(-3675,2600)","0","logical_power","I41";
;
HDL_POWER"P3V3"
CDS_LIB"logical_power";
"A"3;
%"Q_RES"
"2","(-3675,2375)","0","pure_quanta","I42";
;
PART_NUMBER"CS00002JB13"
VALUE"0"
TOLERANCE"5%"
MATERIAL"EMPTY"
WATTAGE"1/16W"
PACK_TYPE"0402LF"
LOCATION"PR403"
CDS_LIB"pure_quanta"
$SEC"1"
CDS_SEC"1";
"A"
$PN"1"3;
"B"
$PN"2"38;
%"UNIVERSAL_GND"
"1","(-1600,-25)","0","logical_power","I43";
;
HDL_POWER"GND"
CDS_LIB"logical_power";
"A"21;
%"Q_CAP"
"1","(-1375,1600)","0","pure_quanta","I44";
;
PART_NUMBER"TMP_QCH2336K1B12"
PACK_TYPE"0402"
VALUE"3300PF"
VOLTAGE"50V"
TOLERANCE"10%"
MATERIAL"X7R"
LOCATION"PC297_P0_1"
CDS_LIB"pure_quanta"
LOCATION"PC297_P0_1"
$SEC"1"
CDS_SEC"1";
"B"
$PN"2"26;
"A"
$PN"1"7;
%"Q_INDUCTOR4P_14"
"1","(175,575)","0","pure_quanta","I46";
;
PART_NUMBER"CV+15^0TZ04"
MATERIAL"IND"
PART_TYPE"SMLF"
VALUE"150NH"
LOCATION"PL114"
NEEDS_NO_SIZE"TRUE"
CDS_LIB"pure_quanta"
SEC_TYPE""
SEC"1";
"1"
$PN"1"35;
"4"
$PN"4"10;
"3"
$PN"3"30;
"2"
$PN"2"33;
%"Q_CAP"
"1","(-975,1600)","0","pure_quanta","I47";
;
PART_NUMBER"CH5103KEB01"
PACK_TYPE"C0402"
VOLTAGE"16V"
VALUE"1UF"
TOLERANCE"10%"
MATERIAL"X6S"
LOCATION"PC299_P0_1"
CDS_LIB"pure_quanta"
LOCATION"PC299_P0_1"
$SEC"1"
CDS_SEC"1";
"B"
$PN"2"26;
"A"
$PN"1"7;
%"Q_CAP"
"1","(-275,975)","2","pure_quanta","I48";
;
PART_NUMBER"CH4106K1B01"
VOLTAGE"50V"
TOLERANCE"10%"
MATERIAL"X7R"
VALUE"100NF"
PACK_TYPE"C0402"
LOCATION"PC301"
CDS_LIB"pure_quanta"
$SEC"1"
CDS_SEC"1";
"B"
$PN"2"34;
"A"
$PN"1"32;
%"Q_CAP"
"1","(-575,1600)","0","pure_quanta","I49";
;
PART_NUMBER"CH6223MEA01"
TOLERANCE"20%"
PACK_TYPE"C0805"
VOLTAGE"16V"
MATERIAL"X6S"
VALUE"22UF"
LOCATION"PC303_P0_1"
CDS_LIB"pure_quanta"
LOCATION"PC303_P0_1"
$SEC"1"
CDS_SEC"1";
"B"
$PN"2"26;
"A"
$PN"1"7;
%"Q_CAP"
"1","(-175,1600)","0","pure_quanta","I50";
;
PART_NUMBER"CH6223MEA01"
TOLERANCE"20%"
PACK_TYPE"C0805"
MATERIAL"X6S"
VOLTAGE"16V"
VALUE"22UF"
LOCATION"PC305_P0_1"
CDS_LIB"pure_quanta"
LOCATION"PC305_P0_1"
$SEC"1"
CDS_SEC"1";
"B"
$PN"2"26;
"A"
$PN"1"7;
%"Q_RES"
"1","(25,-2675)","0","pure_quanta","I51";
;
PART_NUMBER"CS00002JB13"
WATTAGE"1/16W"
PACK_TYPE"0402LF"
VALUE"0"
MATERIAL"CHIP"
TOLERANCE"5%"
LOCATION"PR154"
CDS_LIB"pure_quanta"
$SEC"1"
CDS_SEC"1";
"B"
$PN"2"6;
"A"
$PN"1"50;
%"UNIVERSAL_GND"
"1","(325,-1650)","0","logical_power","I53";
;
HDL_POWER"GND"
CDS_LIB"logical_power";
"A"22;
%"Q_CAP"
"1","(100,-1225)","0","pure_quanta","I54";
;
PART_NUMBER"CH6223MEA01"
TOLERANCE"20%"
PACK_TYPE"C0805"
VOLTAGE"16V"
VALUE"22UF"
MATERIAL"X6S"
LOCATION"PC306_P0_2"
CDS_LIB"pure_quanta"
LOCATION"PC306_P0_2"
$SEC"1"
CDS_SEC"1";
"B"
$PN"2"22;
"A"
$PN"1"4;
%"VCC15"
"1","(325,-850)","0","logical_power","I55";
;
HDL_POWER"SW_P12V_PVCCIN_CPU0_FLT"
CDS_LIB"logical_power";
"A"4;
%"Q_CAPP"
"1","(1950,-525)","0","pure_quanta","I56";
;
PART_NUMBER"CC7560JMD16"
TOLERANCE"20%"
VOLTAGE"2.5V"
MATERIAL"OSCON"
PACK_TYPE"THLF"
VALUE"560UF"
LOCATION"PC16"
CDS_LIB"pure_quanta"
$SEC"1"
CDS_SEC"1";
"A"
$PN"1"9;
"B"
$PN"2"24;
%"Q_CAP"
"1","(2900,-2450)","0","pure_quanta","I57";
;
PART_NUMBER"CH622KMEA03"
TOLERANCE"20%"
VOLTAGE"4V"
VALUE"22UF"
MATERIAL"X6S"
PACK_TYPE"C0805"
LOCATION"PC311_P0_2"
CDS_LIB"pure_quanta"
LOCATION"PC311_P0_2"
$SEC"1"
CDS_SEC"1";
"B"
$PN"2"25;
"A"
$PN"1"6;
%"Q_CAP"
"1","(3325,-2450)","0","pure_quanta","I58";
;
PART_NUMBER"CH622KMEA03"
TOLERANCE"20%"
PACK_TYPE"C0805"
MATERIAL"X6S"
VALUE"22UF"
VOLTAGE"4V"
LOCATION"PC313_P0_2"
CDS_LIB"pure_quanta"
LOCATION"PC313_P0_2"
$SEC"1"
CDS_SEC"1";
"B"
$PN"2"25;
"A"
$PN"1"6;
%"Q_RES"
"2","(3725,-2450)","0","pure_quanta","I59";
;
PART_NUMBER"CS14992FB06"
MATERIAL"CHIP"
WATTAGE"1/16W"
TOLERANCE"1%"
VALUE"499"
PACK_TYPE"0402LF"
LOCATION"PR4219"
CDS_LIB"pure_quanta"
BOM_COST"VR_PCH"
$SEC"1"
CDS_SEC"1";
"A"
$PN"1"6;
"B"
$PN"2"25;
%"ISL99390FRZTR5935"
"1","(-2275,-2125)","0","pure_quanta","I6";
;
PART_NUMBER"AL099390004"
VALUE"ISL99390FRZ-TR5935"
MATERIAL"IC"
PART_TYPE"SMLF"
LOCATION"PU12_P0_2"
NEEDS_NO_SIZE"TRUE"
CDS_LMAN_SYM_OUTLINE"-300,700,250,-650"
CDS_LIB"pure_quanta"
SEC_TYPE""
SEC"1";
"PGND2"
$PN"7_9-20_24"16;
"GL2"
$PN"41"0;
"GL1"
$PN"6"0;
"DNC"
$PN"31"0;
"EN"
$PN"35"51;
"PGND3"
$PN"40"16;
"VOS"
$PN"1"50;
"VIN2"
$PN"30"4;
"PGND1"
$PN"5"16;
"SW"
$PN"10_19"47;
"LSET"
$PN"37"56;
"IOUT"
$PN"38"52;
"TOUT_FLT"
$PN"36"54;
"PVCC"
$PN"4"1;
"PHASE"
$PN"32"48;
"VIN1"
$PN"25_29"4;
"BOOT"
$PN"33"49;
"AGND"
$PN"2"16;
"VCC"
$PN"3"51;
"REFIN"
$PN"39"53;
"PWM"
$PN"34"55;
%"Q_CAPP"
"1","(2525,-1425)","0","pure_quanta","I60";
;
PART_NUMBER"CH733LY8802"
VOLTAGE"2.5V"
MATERIAL"EMPTY"
PACK_TYPE"SMLF"
TOLERANCE"+10/-35%"
VALUE"330UF"
LOCATION"PC2336"
CDS_LIB"pure_quanta"
$SEC"1"
CDS_SEC"1";
"A"
$PN"1"5;
"B"
$PN"2"23;
%"Q_CAPP"
"1","(2425,-550)","0","pure_quanta","I61";
;
PART_NUMBER"CC7560JMD16"
VALUE"560UF"
MATERIAL"OSCON"
TOLERANCE"20%"
VOLTAGE"2.5V"
PACK_TYPE"THLF"
LOCATION"PC316"
CDS_LIB"pure_quanta"
LOCATION"PC316"
$SEC"1"
CDS_SEC"1";
"A"
$PN"1"9;
"B"
$PN"2"24;
%"Q_CAPP"
"1","(2950,-550)","0","pure_quanta","I62";
;
PART_NUMBER"CC7560JMD16"
PACK_TYPE"THLF"
MATERIAL"OSCON"
VALUE"560UF"
TOLERANCE"20%"
VOLTAGE"2.5V"
LOCATION"PC319"
CDS_LIB"pure_quanta"
LOCATION"PC319"
$SEC"1"
CDS_SEC"1";
"A"
$PN"1"9;
"B"
$PN"2"24;
%"Q_CAPP"
"1","(3025,-1400)","0","pure_quanta","I63";
;
PART_NUMBER"CH733LY8802"
VOLTAGE"2.5V"
TOLERANCE"+10/-35%"
VALUE"330UF"
PACK_TYPE"SMLF"
MATERIAL"EMPTY"
LOCATION"PC1920"
CDS_LIB"pure_quanta"
$SEC"1"
CDS_SEC"1";
"A"
$PN"1"5;
"B"
$PN"2"23;
%"Q_CAPP"
"1","(3475,-1425)","0","pure_quanta","I64";
;
PART_NUMBER"CH733LY8802"
VOLTAGE"2.5V"
MATERIAL"EMPTY"
TOLERANCE"+10/-35%"
VALUE"330UF"
PACK_TYPE"SMLF"
LOCATION"PC323"
CDS_LIB"pure_quanta"
LOCATION"PC323"
$SEC"1"
CDS_SEC"1";
"A"
$PN"1"5;
"B"
$PN"2"23;
%"UNIVERSAL_GND"
"1","(3975,-1750)","0","logical_power","I65";
;
HDL_POWER"GND"
CDS_LIB"logical_power";
"A"23;
%"Q_CAPP"
"1","(3975,-1425)","0","pure_quanta","I66";
;
PART_NUMBER"CH733LY8802"
VOLTAGE"2.5V"
TOLERANCE"+10/-35%"
VALUE"330UF"
PACK_TYPE"SMLF"
MATERIAL"EMPTY"
LOCATION"PC326"
CDS_LIB"pure_quanta"
LOCATION"PC326"
$SEC"1"
CDS_SEC"1";
"A"
$PN"1"5;
"B"
$PN"2"23;
%"Q_CAPP"
"1","(3475,-550)","0","pure_quanta","I67";
;
PART_NUMBER"CC7560JMD16"
VOLTAGE"2.5V"
MATERIAL"OSCON"
PACK_TYPE"THLF"
VALUE"560UF"
TOLERANCE"20%"
LOCATION"PC322"
CDS_LIB"pure_quanta"
LOCATION"PC322"
$SEC"1"
CDS_SEC"1";
"A"
$PN"1"9;
"B"
$PN"2"24;
%"VCC15"
"1","(3975,-1100)","0","logical_power","I68";
;
HDL_POWER"PVCCIN_CPU0"
CDS_LIB"logical_power";
"A"5;
%"UNIVERSAL_GND"
"1","(3975,-875)","0","logical_power","I69";
;
HDL_POWER"GND"
CDS_LIB"logical_power";
"A"24;
%"Q_CAPP"
"1","(3975,-550)","0","pure_quanta","I70";
;
PART_NUMBER"CC7560JMD16"
PACK_TYPE"THLF"
VALUE"560UF"
TOLERANCE"20%"
MATERIAL"OSCON"
VOLTAGE"2.5V"
LOCATION"PC325"
CDS_LIB"pure_quanta"
LOCATION"PC325"
$SEC"1"
CDS_SEC"1";
"A"
$PN"1"9;
"B"
$PN"2"24;
%"UNIVERSAL_GND"
"1","(4025,-2875)","0","logical_power","I71";
;
HDL_POWER"GND"
CDS_LIB"logical_power";
"A"25;
%"VCC15"
"1","(4025,-2075)","0","logical_power","I72";
;
HDL_POWER"PVCCIN_CPU0"
CDS_LIB"logical_power";
"A"6;
%"Q_RES"
"1","(100,100)","0","pure_quanta","I73";
;
PART_NUMBER"CS00002JB13"
PACK_TYPE"0402LF"
WATTAGE"1/16W"
TOLERANCE"5%"
MATERIAL"CHIP"
VALUE"0"
LOCATION"PR155"
CDS_LIB"pure_quanta"
$SEC"1"
CDS_SEC"1";
"B"
$PN"2"10;
"A"
$PN"1"37;
%"UNIVERSAL_GND"
"1","(350,1175)","0","logical_power","I74";
;
HDL_POWER"GND"
CDS_LIB"logical_power";
"A"26;
%"Q_CAP"
"1","(200,1600)","0","pure_quanta","I75";
;
PART_NUMBER"CH6223MEA01"
TOLERANCE"20%"
PACK_TYPE"C0805"
VALUE"22UF"
MATERIAL"X6S"
VOLTAGE"16V"
LOCATION"PC307_P0_1"
CDS_LIB"pure_quanta"
LOCATION"PC307_P0_1"
$SEC"1"
CDS_SEC"1";
"B"
$PN"2"26;
"A"
$PN"1"7;
%"GND"
"1","(1450,1575)","0","logical_power","I77";
;
HDL_POWER"GND"
SIZE"1B"
CDS_LIB"logical_power";
"A<SIZE-1..0>\NAC"27;
%"VCC15"
"1","(350,1975)","0","logical_power","I78";
;
HDL_POWER"SW_P12V_PVCCIN_CPU0_FLT"
CDS_LIB"logical_power";
"A"7;
%"VCC15"
"1","(1450,2200)","0","logical_power","I79";
;
HDL_POWER"P12V_AUX"
CDS_LIB"logical_power";
"A"8;
%"Q_CAP"
"1","(1450,1825)","2","pure_quanta","I80";
;
PART_NUMBER"CH4106K1B01"
PACK_TYPE"C0402"
VALUE"100NF"
MATERIAL"X7R"
TOLERANCE"10%"
VOLTAGE"50V"
LOCATION"PC1652"
CDS_LIB"pure_quanta"
$SEC"1"
CDS_SEC"1";
"B"
$PN"2"27;
"A"
$PN"1"8;
%"Q_RES"
"1","(1875,1900)","0","pure_quanta","I81";
;
PART_NUMBER"TMP_QCS+0308BR00"
VALUE"0.03"
TOLERANCE"0.1%"
PACK_TYPE"2512LF"
MATERIAL"EMPTY"
WATTAGE"1W"
LOCATION"PR2554"
CDS_LIB"pure_quanta"
$SEC"1"
CDS_SEC"1";
"B"
$PN"2"11;
"A"
$PN"1"8;
%"Q_INDUCTOR"
"1","(1875,2050)","0","pure_quanta","I82";
;
PART_NUMBER"CVA50^0EZ01"
VALUE"50NH/148A"
PACK_TYPE"SMLF"
MATERIAL"IND"
LOCATION"PL15"
CDS_LIB"pure_quanta"
NEEDS_NO_SIZE"TRUE"
$SEC"1"
CDS_SEC"1";
"1"
$PN"1"8;
"2"
$PN"2"11;
%"Q_CAP"
"1","(1975,500)","0","pure_quanta","I83";
;
PART_NUMBER"CH4106K1B01"
VOLTAGE"50V"
TOLERANCE"10%"
MATERIAL"X7R"
PACK_TYPE"C0402"
VALUE"100NF"
LOCATION"PC308_P0_1"
CDS_LIB"pure_quanta"
LOCATION"PC308_P0_1"
$SEC"1"
CDS_SEC"1";
"B"
$PN"2"28;
"A"
$PN"1"10;
%"Q_CAP"
"1","(2375,500)","0","pure_quanta","I84";
;
PART_NUMBER"CH5103KEB01"
MATERIAL"X6S"
TOLERANCE"10%"
VALUE"1UF"
VOLTAGE"16V"
PACK_TYPE"C0402"
LOCATION"PC310_P0_1"
CDS_LIB"pure_quanta"
LOCATION"PC310_P0_1"
$SEC"1"
CDS_SEC"1";
"B"
$PN"2"28;
"A"
$PN"1"10;
%"Q_CAP"
"1","(2800,500)","0","pure_quanta","I85";
;
PART_NUMBER"CH622KMEA03"
TOLERANCE"20%"
PACK_TYPE"C0805"
MATERIAL"X6S"
VALUE"22UF"
VOLTAGE"4V"
LOCATION"PC312_P0_1"
CDS_LIB"pure_quanta"
LOCATION"PC312_P0_1"
$SEC"1"
CDS_SEC"1";
"B"
$PN"2"28;
"A"
$PN"1"10;
%"Q_CAP"
"1","(3225,500)","0","pure_quanta","I86";
;
PART_NUMBER"CH622KMEA03"
VOLTAGE"4V"
VALUE"22UF"
TOLERANCE"20%"
PACK_TYPE"C0805"
MATERIAL"X6S"
LOCATION"PC314_P0_1"
CDS_LIB"pure_quanta"
LOCATION"PC314_P0_1"
$SEC"1"
CDS_SEC"1";
"B"
$PN"2"28;
"A"
$PN"1"10;
%"UNIVERSAL_GND"
"1","(3525,125)","0","logical_power","I87";
;
HDL_POWER"GND"
CDS_LIB"logical_power";
"A"28;
%"VCC15"
"1","(3975,-225)","0","logical_power","I88";
;
HDL_POWER"PVCCIN_CPU0"
CDS_LIB"logical_power";
"A"9;
%"VCC15"
"1","(3525,900)","0","logical_power","I89";
;
HDL_POWER"PVCCIN_CPU0"
CDS_LIB"logical_power";
"A"10;
%"Q_CAP"
"1","(-3800,-1625)","0","pure_quanta","I9";
;
PART_NUMBER"CH5222KEB01"
PACK_TYPE"C0402"
VOLTAGE"10V"
VALUE"2.2UF"
TOLERANCE"10%"
MATERIAL"X6S"
LOCATION"PC292"
CDS_LIB"pure_quanta"
LOCATION"PC292"
$SEC"1"
CDS_SEC"1";
"B"
$PN"2"14;
"A"
$PN"1"51;
%"UNIVERSAL_GND"
"1","(3950,1500)","0","logical_power","I90";
;
HDL_POWER"GND"
CDS_LIB"logical_power";
"A"29;
%"Q_CAPP"
"1","(2350,1825)","0","pure_quanta","I91";
;
PART_NUMBER"CC72703MD38"
VOLTAGE"16V"
PACK_TYPE"THLF"
VALUE"270UF"
TOLERANCE"20%"
MATERIAL"OSCON"
LOCATION"PC315"
CDS_LIB"pure_quanta"
LOCATION"PC315"
$SEC"1"
CDS_SEC"1";
"A"
$PN"1"11;
"B"
$PN"2"29;
%"Q_CAPP"
"1","(2750,1825)","0","pure_quanta","I92";
;
PART_NUMBER"CC72703MD38"
TOLERANCE"20%"
VALUE"270UF"
MATERIAL"OSCON"
VOLTAGE"16V"
PACK_TYPE"THLF"
LOCATION"PC318"
CDS_LIB"pure_quanta"
LOCATION"PC318"
$SEC"1"
CDS_SEC"1";
"A"
$PN"1"11;
"B"
$PN"2"29;
%"Q_CAPP"
"1","(3150,1825)","0","pure_quanta","I93";
;
PART_NUMBER"CC72703MD38"
MATERIAL"OSCON"
VALUE"270UF"
TOLERANCE"20%"
PACK_TYPE"THLF"
VOLTAGE"16V"
LOCATION"PC321"
CDS_LIB"pure_quanta"
LOCATION"PC321"
$SEC"1"
CDS_SEC"1";
"A"
$PN"1"11;
"B"
$PN"2"29;
%"Q_CAPP"
"1","(3550,1825)","0","pure_quanta","I94";
;
PART_NUMBER"CC72703MD38"
VOLTAGE"16V"
TOLERANCE"20%"
MATERIAL"OSCON"
VALUE"270UF"
PACK_TYPE"THLF"
LOCATION"PC324"
CDS_LIB"pure_quanta"
LOCATION"PC324"
$SEC"1"
CDS_SEC"1";
"A"
$PN"1"11;
"B"
$PN"2"29;
%"Q_CAPP"
"1","(3950,1825)","0","pure_quanta","I95";
;
PART_NUMBER"CC72703MD38"
PACK_TYPE"THLF"
TOLERANCE"20%"
VOLTAGE"16V"
MATERIAL"OSCON"
VALUE"270UF"
LOCATION"PC2345"
CDS_LIB"pure_quanta"
$SEC"1"
CDS_SEC"1";
"A"
$PN"1"11;
"B"
$PN"2"29;
%"VCC15"
"1","(3950,2150)","0","logical_power","I96";
;
HDL_POWER"SW_P12V_PVCCIN_CPU0_FLT"
CDS_LIB"logical_power";
"A"11;
%"Q_RES"
"1","(-1000,1150)","0","pure_quanta","I97";
;
PART_NUMBER"CS-3302FB01"
VALUE"3.3"
WATTAGE"1/16W"
TOLERANCE"1%"
MATERIAL"CHIP"
PACK_TYPE"0402LF"
LOCATION"PR1787"
CDS_LIB"pure_quanta"
$SEC"1"
CDS_SEC"1";
"B"
$PN"2"32;
"A"
$PN"1"36;
END.
